# T6G (Grand Teton) — schematic netlist excerpt (pin names and nets, part order shuffled) for the footprints in the layout excerpt that follows; sources: Cadence DE-HDL packaged netlist, KiCad conversion of 04192023_DAF0TMB3IC0_F0TG_MB_C_brd_V02_OCP.brd

R3278  Q_RES  1K 1% CHIP  pkg 0402LF  page 111 : A = FM_P2E_EQA0 ; B = GND
R579  Q_RES  4.75K 1% CHIP  pkg 0402LF  page 183 : A = CLK_9ZXL045_P1_SADR0 ; B = GND
C739  Q_CAP_DIFFBUS  DIFF BUS_0.22UF 6.3V 20% X6S  pkg C0201  page 66 : \1\ = P5E_CPU1_P1_TX_C_DP<1> ; \2\ = P5E_CPU1_P1_TX_DP<1>

(kicad_pcb
	(version 20260206)
	(generator "pcbnew")
	(generator_version "10.0")
	(general
		(thickness 1.6)
		(legacy_teardrops no)
	)
	(paper "A4")
	(title_block
		(title "04192023_DAF0TMB3IC0_F0TG_MB_C_brd_V02_OCP.brd")
		(comment 1 "Grand Teton / footprints 1828-1830 of 8354")
	)
	(layers
		(0 "F.Cu" signal "TOP")
		(4 "In1.Cu" signal "GND")
		(6 "In2.Cu" signal "IN1")
		(8 "In3.Cu" signal "GND1")
		(10 "In4.Cu" signal "IN2")
		(12 "In5.Cu" signal "GND2")
		(14 "In6.Cu" signal "IN3")
		(16 "In7.Cu" signal "GND3")
		(18 "In8.Cu" signal "VCC")
		(20 "In9.Cu" signal "VCC1")
		(22 "In10.Cu" signal "GND4")
		(24 "In11.Cu" signal "IN4")
		(26 "In12.Cu" signal "GND5")
		(28 "In13.Cu" signal "IN5")
		(30 "In14.Cu" signal "GND6")
		(32 "In15.Cu" signal "IN6")
		(34 "In16.Cu" signal "GND7")
		(2 "B.Cu" signal "BOTTOM")
		(9 "F.Adhes" user "F.Adhesive")
		(11 "B.Adhes" user "B.Adhesive")
		(13 "F.Paste" user "Package Geometry/Pastemask Top")
		(15 "B.Paste" user "Package Geometry/Pastemask Bottom")
		(5 "F.SilkS" user "Ref Des/Silkscreen Top")
		(7 "B.SilkS" user "Ref Des/Silkscreen Bottom")
		(1 "F.Mask" user "Board Geometry/Soldermask Top")
		(3 "B.Mask" user "Board Geometry/Soldermask Bottom")
		(17 "Dwgs.User" user "User.Drawings")
		(19 "Cmts.User" user "User.Comments")
		(21 "Eco1.User" user "User.Eco1")
		(23 "Eco2.User" user "User.Eco2")
		(25 "Edge.Cuts" user "Board Geometry/Outline")
		(27 "Margin" user)
		(31 "F.CrtYd" user "Package Geometry/Place Bound Top")
		(29 "B.CrtYd" user "Package Geometry/Place Bound Bottom")
		(35 "F.Fab" user "Ref Des/Assembly Top")
		(33 "B.Fab" user "Ref Des/Assembly Bottom")
	)
	(footprint ""
		(layer "F.Cu")
		(at 104.267 -416.814 180)
		(property "Reference" "R579"
			(at 0 0 180)
			(layer "F.SilkS")
			(hide yes)
			(effects
				(font
					(size 1.27 1.27)
				)
			)
		)
		(property "Value" ""
			(at 0 0 180)
			(layer "F.Fab")
			(effects
				(font
					(size 1.27 1.27)
				)
			)
		)
		(duplicate_pad_numbers_are_jumpers no)
		(fp_line
			(start 0.7874 0.4064)
			(end -0.7874 0.4064)
			(stroke
				(width 0.1524)
				(type default)
			)
			(layer "F.SilkS")
		)
		(fp_line
			(start 0.7874 -0.4064)
			(end 0.7874 0.4064)
			(stroke
				(width 0.1524)
				(type default)
			)
			(layer "F.SilkS")
		)
		(fp_line
			(start -0.7874 0.4064)
			(end -0.7874 -0.4064)
			(stroke
				(width 0.1524)
				(type default)
			)
			(layer "F.SilkS")
		)
		(fp_line
			(start -0.7874 -0.4064)
			(end 0.7874 -0.4064)
			(stroke
				(width 0.1524)
				(type default)
			)
			(layer "F.SilkS")
		)
		(fp_line
			(start 0.67945 0.3048)
			(end 0.120396 0.3048)
			(stroke
				(width 0.1)
				(type default)
			)
			(layer "F.Fab")
		)
		(fp_line
			(start 0.67945 -0.3048)
			(end 0.67945 0.3048)
			(stroke
				(width 0.1)
				(type default)
			)
			(layer "F.Fab")
		)
		(fp_line
			(start 0.12065 -0.2794)
			(end 0.12065 -0.3048)
			(stroke
				(width 0.1)
				(type default)
			)
			(layer "F.Fab")
		)
		(fp_line
			(start 0.12065 -0.3048)
			(end 0.67945 -0.3048)
			(stroke
				(width 0.1)
				(type default)
			)
			(layer "F.Fab")
		)
		(fp_line
			(start 0.120396 0.3048)
			(end 0.120396 0.2794)
			(stroke
				(width 0.1)
				(type default)
			)
			(layer "F.Fab")
		)
		(fp_line
			(start 0.120396 0.2794)
			(end -0.12065 0.2794)
			(stroke
				(width 0.1)
				(type default)
			)
			(layer "F.Fab")
		)
		(fp_line
			(start -0.12065 0.3048)
			(end -0.67945 0.3048)
			(stroke
				(width 0.1)
				(type default)
			)
			(layer "F.Fab")
		)
		(fp_line
			(start -0.12065 0.2794)
			(end -0.12065 0.3048)
			(stroke
				(width 0.1)
				(type default)
			)
			(layer "F.Fab")
		)
		(fp_line
			(start -0.12065 -0.2794)
			(end 0.12065 -0.2794)
			(stroke
				(width 0.1)
				(type default)
			)
			(layer "F.Fab")
		)
		(fp_line
			(start -0.12065 -0.305054)
			(end -0.12065 -0.2794)
			(stroke
				(width 0.1)
				(type default)
			)
			(layer "F.Fab")
		)
		(fp_line
			(start -0.67945 0.3048)
			(end -0.67945 -0.305054)
			(stroke
				(width 0.1)
				(type default)
			)
			(layer "F.Fab")
		)
		(fp_line
			(start -0.67945 -0.305054)
			(end -0.12065 -0.305054)
			(stroke
				(width 0.1)
				(type default)
			)
			(layer "F.Fab")
		)
		(pad "1" smd circle
			(at -0.40005 0 180)
			(size 0 0)
			(layers "F.Cu" "F.Mask" "F.Paste")
			(net "CLK_9ZXL045_P1_SADR0")
		)
		(pad "2" smd circle
			(at 0.40005 0 180)
			(size 0 0)
			(layers "F.Cu" "F.Mask" "F.Paste")
			(net "GND")
		)
	)
	(footprint ""
		(layer "F.Cu")
		(at 26.793444 -423.509694 180)
		(property "Reference" "R3278"
			(at 0 0 180)
			(layer "F.SilkS")
			(hide yes)
			(effects
				(font
					(size 1.27 1.27)
				)
			)
		)
		(property "Value" ""
			(at 0 0 180)
			(layer "F.Fab")
			(effects
				(font
					(size 1.27 1.27)
				)
			)
		)
		(duplicate_pad_numbers_are_jumpers no)
		(fp_line
			(start 0.7874 0.4064)
			(end -0.7874 0.4064)
			(stroke
				(width 0.1524)
				(type default)
			)
			(layer "F.SilkS")
		)
		(fp_line
			(start 0.7874 -0.4064)
			(end 0.7874 0.4064)
			(stroke
				(width 0.1524)
				(type default)
			)
			(layer "F.SilkS")
		)
		(fp_line
			(start -0.7874 0.4064)
			(end -0.7874 -0.4064)
			(stroke
				(width 0.1524)
				(type default)
			)
			(layer "F.SilkS")
		)
		(fp_line
			(start -0.7874 -0.4064)
			(end 0.7874 -0.4064)
			(stroke
				(width 0.1524)
				(type default)
			)
			(layer "F.SilkS")
		)
		(fp_line
			(start 0.67945 0.3048)
			(end 0.120396 0.3048)
			(stroke
				(width 0.1)
				(type default)
			)
			(layer "F.Fab")
		)
		(fp_line
			(start 0.67945 -0.3048)
			(end 0.67945 0.3048)
			(stroke
				(width 0.1)
				(type default)
			)
			(layer "F.Fab")
		)
		(fp_line
			(start 0.12065 -0.2794)
			(end 0.12065 -0.3048)
			(stroke
				(width 0.1)
				(type default)
			)
			(layer "F.Fab")
		)
		(fp_line
			(start 0.12065 -0.3048)
			(end 0.67945 -0.3048)
			(stroke
				(width 0.1)
				(type default)
			)
			(layer "F.Fab")
		)
		(fp_line
			(start 0.120396 0.3048)
			(end 0.120396 0.2794)
			(stroke
				(width 0.1)
				(type default)
			)
			(layer "F.Fab")
		)
		(fp_line
			(start 0.120396 0.2794)
			(end -0.12065 0.2794)
			(stroke
				(width 0.1)
				(type default)
			)
			(layer "F.Fab")
		)
		(fp_line
			(start -0.12065 0.3048)
			(end -0.67945 0.3048)
			(stroke
				(width 0.1)
				(type default)
			)
			(layer "F.Fab")
		)
		(fp_line
			(start -0.12065 0.2794)
			(end -0.12065 0.3048)
			(stroke
				(width 0.1)
				(type default)
			)
			(layer "F.Fab")
		)
		(fp_line
			(start -0.12065 -0.2794)
			(end 0.12065 -0.2794)
			(stroke
				(width 0.1)
				(type default)
			)
			(layer "F.Fab")
		)
		(fp_line
			(start -0.12065 -0.305054)
			(end -0.12065 -0.2794)
			(stroke
				(width 0.1)
				(type default)
			)
			(layer "F.Fab")
		)
		(fp_line
			(start -0.67945 0.3048)
			(end -0.67945 -0.305054)
			(stroke
				(width 0.1)
				(type default)
			)
			(layer "F.Fab")
		)
		(fp_line
			(start -0.67945 -0.305054)
			(end -0.12065 -0.305054)
			(stroke
				(width 0.1)
				(type default)
			)
			(layer "F.Fab")
		)
		(pad "1" smd circle
			(at -0.40005 0 180)
			(size 0 0)
			(layers "F.Cu" "F.Mask" "F.Paste")
			(net "FM_P2E_EQA0")
		)
		(pad "2" smd circle
			(at 0.40005 0 180)
			(size 0 0)
			(layers "F.Cu" "F.Mask" "F.Paste")
			(net "GND")
		)
	)
	(footprint ""
		(layer "F.Cu")
		(at 75.49515 -375.94286 180)
		(property "Reference" "C739"
			(at 0 0 180)
			(layer "F.SilkS")
			(hide yes)
			(effects
				(font
					(size 1.27 1.27)
				)
			)
		)
		(property "Value" ""
			(at 0 0 180)
			(layer "F.Fab")
			(effects
				(font
					(size 1.27 1.27)
				)
			)
		)
		(duplicate_pad_numbers_are_jumpers no)
		(fp_line
			(start 0.299974 0.150114)
			(end -0.299974 0.150114)
			(stroke
				(width 0.1)
				(type default)
			)
			(layer "F.Fab")
		)
		(fp_line
			(start 0.299974 -0.150114)
			(end 0.299974 0.150114)
			(stroke
				(width 0.1)
				(type default)
			)
			(layer "F.Fab")
		)
		(fp_line
			(start -0.299974 0.150114)
			(end -0.299974 -0.150114)
			(stroke
				(width 0.1)
				(type default)
			)
			(layer "F.Fab")
		)
		(fp_line
			(start -0.299974 -0.150114)
			(end 0.299974 -0.150114)
			(stroke
				(width 0.1)
				(type default)
			)
			(layer "F.Fab")
		)
		(pad "1" smd rect
			(at -0.2667 0 180)
			(size 0.3048 0.381)
			(layers "F.Cu" "F.Mask" "F.Paste")
			(net "P5E_CPU1_P1_TX_C_DP<1>")
		)
		(pad "2" smd rect
			(at 0.2667 0 180)
			(size 0.3048 0.381)
			(layers "F.Cu" "F.Mask" "F.Paste")
			(net "P5E_CPU1_P1_TX_DP<1>")
		)
	)
)
